(kicad_pcb
	(version 20260206)
	(generator "pcbnew")
	(generator_version "10.0")
	(general
		(thickness 1.6)
		(legacy_teardrops no)
	)
	(paper "A4")
	(title_block
		(title "01162023_DA0F0TEBIF0_F0T_Expander_BD_F_brd_V02_OCP.brd")
		(comment 1 "Grand Teton / footprints 5631-5637 of 9728")
	)
	(layers
		(0 "F.Cu" signal "TOP")
		(4 "In1.Cu" signal "GND")
		(6 "In2.Cu" signal "VCC")
		(8 "In3.Cu" signal "VCC1")
		(10 "In4.Cu" signal "GND1")
		(12 "In5.Cu" signal "IN1")
		(14 "In6.Cu" signal "GND2")
		(16 "In7.Cu" signal "IN2")
		(18 "In8.Cu" signal "GND3")
		(20 "In9.Cu" signal "IN3")
		(22 "In10.Cu" signal "GND4")
		(24 "In11.Cu" signal "IN4")
		(26 "In12.Cu" signal "GND5")
		(28 "In13.Cu" signal "IN5")
		(30 "In14.Cu" signal "GND6")
		(32 "In15.Cu" signal "IN6")
		(34 "In16.Cu" signal "GND7")
		(2 "B.Cu" signal "BOTTOM")
		(9 "F.Adhes" user "F.Adhesive")
		(11 "B.Adhes" user "B.Adhesive")
		(13 "F.Paste" user "Package Geometry/Pastemask Top")
		(15 "B.Paste" user "Package Geometry/Pastemask Bottom")
		(5 "F.SilkS" user "Ref Des/Silkscreen Top")
		(7 "B.SilkS" user "Ref Des/Silkscreen Bottom")
		(1 "F.Mask" user "Board Geometry/Soldermask Top")
		(3 "B.Mask" user "Board Geometry/Soldermask Bottom")
		(17 "Dwgs.User" user "User.Drawings")
		(19 "Cmts.User" user "User.Comments")
		(21 "Eco1.User" user "User.Eco1")
		(23 "Eco2.User" user "User.Eco2")
		(25 "Edge.Cuts" user "Board Geometry/Outline")
		(27 "Margin" user)
		(31 "F.CrtYd" user "Package Geometry/Place Bound Top")
		(29 "B.CrtYd" user "Package Geometry/Place Bound Bottom")
		(35 "F.Fab" user "Ref Des/Assembly Top")
		(33 "B.Fab" user "Ref Des/Assembly Bottom")
	)
	(footprint ""
		(layer "F.Cu")
		(at 451.122034 -212.063076 90)
		(property "Reference" "C2613"
			(at 0 0 90)
			(layer "F.SilkS")
			(hide yes)
			(effects
				(font
					(size 1.27 1.27)
				)
			)
		)
		(property "Value" ""
			(at 0 0 90)
			(layer "F.Fab")
			(effects
				(font
					(size 1.27 1.27)
				)
			)
		)
		(duplicate_pad_numbers_are_jumpers no)
		(fp_line
			(start 0.7874 -0.4064)
			(end 0.7874 0.4064)
			(stroke
				(width 0.1524)
				(type default)
			)
			(layer "F.SilkS")
		)
		(fp_line
			(start -0.7874 -0.4064)
			(end 0.7874 -0.4064)
			(stroke
				(width 0.1524)
				(type default)
			)
			(layer "F.SilkS")
		)
		(fp_line
			(start 0.7874 0.4064)
			(end -0.7874 0.4064)
			(stroke
				(width 0.1524)
				(type default)
			)
			(layer "F.SilkS")
		)
		(fp_line
			(start -0.7874 0.4064)
			(end -0.7874 -0.4064)
			(stroke
				(width 0.1524)
				(type default)
			)
			(layer "F.SilkS")
		)
		(fp_line
			(start -0.12065 -0.305054)
			(end -0.12065 -0.2794)
			(stroke
				(width 0.1)
				(type default)
			)
			(layer "F.Fab")
		)
		(fp_line
			(start -0.67945 -0.305054)
			(end -0.12065 -0.305054)
			(stroke
				(width 0.1)
				(type default)
			)
			(layer "F.Fab")
		)
		(fp_line
			(start 0.67945 -0.3048)
			(end 0.67945 0.3048)
			(stroke
				(width 0.1)
				(type default)
			)
			(layer "F.Fab")
		)
		(fp_line
			(start 0.12065 -0.3048)
			(end 0.67945 -0.3048)
			(stroke
				(width 0.1)
				(type default)
			)
			(layer "F.Fab")
		)
		(fp_line
			(start 0.12065 -0.2794)
			(end 0.12065 -0.3048)
			(stroke
				(width 0.1)
				(type default)
			)
			(layer "F.Fab")
		)
		(fp_line
			(start -0.12065 -0.2794)
			(end 0.12065 -0.2794)
			(stroke
				(width 0.1)
				(type default)
			)
			(layer "F.Fab")
		)
		(fp_line
			(start 0.120396 0.2794)
			(end -0.12065 0.2794)
			(stroke
				(width 0.1)
				(type default)
			)
			(layer "F.Fab")
		)
		(fp_line
			(start -0.12065 0.2794)
			(end -0.12065 0.3048)
			(stroke
				(width 0.1)
				(type default)
			)
			(layer "F.Fab")
		)
		(fp_line
			(start 0.67945 0.3048)
			(end 0.120396 0.3048)
			(stroke
				(width 0.1)
				(type default)
			)
			(layer "F.Fab")
		)
		(fp_line
			(start 0.120396 0.3048)
			(end 0.120396 0.2794)
			(stroke
				(width 0.1)
				(type default)
			)
			(layer "F.Fab")
		)
		(fp_line
			(start -0.12065 0.3048)
			(end -0.67945 0.3048)
			(stroke
				(width 0.1)
				(type default)
			)
			(layer "F.Fab")
		)
		(fp_line
			(start -0.67945 0.3048)
			(end -0.67945 -0.305054)
			(stroke
				(width 0.1)
				(type default)
			)
			(layer "F.Fab")
		)
		(pad "1" smd circle
			(at -0.40005 0 90)
			(size 0 0)
			(layers "F.Cu" "F.Mask" "F.Paste")
			(net "USB_VBUS_CONN")
		)
		(pad "2" smd circle
			(at 0.40005 0 90)
			(size 0 0)
			(layers "F.Cu" "F.Mask" "F.Paste")
			(net "GND")
		)
	)
	(footprint ""
		(layer "F.Cu")
		(at 248.819924 -87.150448 180)
		(property "Reference" "R1465"
			(at 0 0 180)
			(layer "F.SilkS")
			(hide yes)
			(effects
				(font
					(size 1.27 1.27)
				)
			)
		)
		(property "Value" ""
			(at 0 0 180)
			(layer "F.Fab")
			(effects
				(font
					(size 1.27 1.27)
				)
			)
		)
		(duplicate_pad_numbers_are_jumpers no)
		(fp_line
			(start 0.7874 0.4064)
			(end -0.7874 0.4064)
			(stroke
				(width 0.1524)
				(type default)
			)
			(layer "F.SilkS")
		)
		(fp_line
			(start 0.7874 -0.4064)
			(end 0.7874 0.4064)
			(stroke
				(width 0.1524)
				(type default)
			)
			(layer "F.SilkS")
		)
		(fp_line
			(start -0.7874 0.4064)
			(end -0.7874 -0.4064)
			(stroke
				(width 0.1524)
				(type default)
			)
			(layer "F.SilkS")
		)
		(fp_line
			(start -0.7874 -0.4064)
			(end 0.7874 -0.4064)
			(stroke
				(width 0.1524)
				(type default)
			)
			(layer "F.SilkS")
		)
		(fp_line
			(start 0.67945 0.3048)
			(end 0.120396 0.3048)
			(stroke
				(width 0.1)
				(type default)
			)
			(layer "F.Fab")
		)
		(fp_line
			(start 0.67945 -0.3048)
			(end 0.67945 0.3048)
			(stroke
				(width 0.1)
				(type default)
			)
			(layer "F.Fab")
		)
		(fp_line
			(start 0.12065 -0.2794)
			(end 0.12065 -0.3048)
			(stroke
				(width 0.1)
				(type default)
			)
			(layer "F.Fab")
		)
		(fp_line
			(start 0.12065 -0.3048)
			(end 0.67945 -0.3048)
			(stroke
				(width 0.1)
				(type default)
			)
			(layer "F.Fab")
		)
		(fp_line
			(start 0.120396 0.3048)
			(end 0.120396 0.2794)
			(stroke
				(width 0.1)
				(type default)
			)
			(layer "F.Fab")
		)
		(fp_line
			(start 0.120396 0.2794)
			(end -0.12065 0.2794)
			(stroke
				(width 0.1)
				(type default)
			)
			(layer "F.Fab")
		)
		(fp_line
			(start -0.12065 0.3048)
			(end -0.67945 0.3048)
			(stroke
				(width 0.1)
				(type default)
			)
			(layer "F.Fab")
		)
		(fp_line
			(start -0.12065 0.2794)
			(end -0.12065 0.3048)
			(stroke
				(width 0.1)
				(type default)
			)
			(layer "F.Fab")
		)
		(fp_line
			(start -0.12065 -0.2794)
			(end 0.12065 -0.2794)
			(stroke
				(width 0.1)
				(type default)
			)
			(layer "F.Fab")
		)
		(fp_line
			(start -0.12065 -0.305054)
			(end -0.12065 -0.2794)
			(stroke
				(width 0.1)
				(type default)
			)
			(layer "F.Fab")
		)
		(fp_line
			(start -0.67945 0.3048)
			(end -0.67945 -0.305054)
			(stroke
				(width 0.1)
				(type default)
			)
			(layer "F.Fab")
		)
		(fp_line
			(start -0.67945 -0.305054)
			(end -0.12065 -0.305054)
			(stroke
				(width 0.1)
				(type default)
			)
			(layer "F.Fab")
		)
		(pad "1" smd circle
			(at -0.40005 0 180)
			(size 0 0)
			(layers "F.Cu" "F.Mask" "F.Paste")
			(net "SMB_CK440_CLK_SCL")
		)
		(pad "2" smd circle
			(at 0.40005 0 180)
			(size 0 0)
			(layers "F.Cu" "F.Mask" "F.Paste")
			(net "SMB_CLK_ISO_R_SCL_R1")
		)
	)
	(footprint ""
		(layer "F.Cu")
		(at 275.710396 -414.88995 90)
		(property "Reference" "R1810"
			(at 0 0 90)
			(layer "F.SilkS")
			(hide yes)
			(effects
				(font
					(size 1.27 1.27)
				)
			)
		)
		(property "Value" ""
			(at 0 0 90)
			(layer "F.Fab")
			(effects
				(font
					(size 1.27 1.27)
				)
			)
		)
		(duplicate_pad_numbers_are_jumpers no)
		(fp_line
			(start 0.7874 -0.4064)
			(end 0.7874 0.4064)
			(stroke
				(width 0.1524)
				(type default)
			)
			(layer "F.SilkS")
		)
		(fp_line
			(start -0.7874 -0.4064)
			(end 0.7874 -0.4064)
			(stroke
				(width 0.1524)
				(type default)
			)
			(layer "F.SilkS")
		)
		(fp_line
			(start 0.7874 0.4064)
			(end -0.7874 0.4064)
			(stroke
				(width 0.1524)
				(type default)
			)
			(layer "F.SilkS")
		)
		(fp_line
			(start -0.7874 0.4064)
			(end -0.7874 -0.4064)
			(stroke
				(width 0.1524)
				(type default)
			)
			(layer "F.SilkS")
		)
		(fp_line
			(start -0.12065 -0.305054)
			(end -0.12065 -0.2794)
			(stroke
				(width 0.1)
				(type default)
			)
			(layer "F.Fab")
		)
		(fp_line
			(start -0.67945 -0.305054)
			(end -0.12065 -0.305054)
			(stroke
				(width 0.1)
				(type default)
			)
			(layer "F.Fab")
		)
		(fp_line
			(start 0.67945 -0.3048)
			(end 0.67945 0.3048)
			(stroke
				(width 0.1)
				(type default)
			)
			(layer "F.Fab")
		)
		(fp_line
			(start 0.12065 -0.3048)
			(end 0.67945 -0.3048)
			(stroke
				(width 0.1)
				(type default)
			)
			(layer "F.Fab")
		)
		(fp_line
			(start 0.12065 -0.2794)
			(end 0.12065 -0.3048)
			(stroke
				(width 0.1)
				(type default)
			)
			(layer "F.Fab")
		)
		(fp_line
			(start -0.12065 -0.2794)
			(end 0.12065 -0.2794)
			(stroke
				(width 0.1)
				(type default)
			)
			(layer "F.Fab")
		)
		(fp_line
			(start 0.120396 0.2794)
			(end -0.12065 0.2794)
			(stroke
				(width 0.1)
				(type default)
			)
			(layer "F.Fab")
		)
		(fp_line
			(start -0.12065 0.2794)
			(end -0.12065 0.3048)
			(stroke
				(width 0.1)
				(type default)
			)
			(layer "F.Fab")
		)
		(fp_line
			(start 0.67945 0.3048)
			(end 0.120396 0.3048)
			(stroke
				(width 0.1)
				(type default)
			)
			(layer "F.Fab")
		)
		(fp_line
			(start 0.120396 0.3048)
			(end 0.120396 0.2794)
			(stroke
				(width 0.1)
				(type default)
			)
			(layer "F.Fab")
		)
		(fp_line
			(start -0.12065 0.3048)
			(end -0.67945 0.3048)
			(stroke
				(width 0.1)
				(type default)
			)
			(layer "F.Fab")
		)
		(fp_line
			(start -0.67945 0.3048)
			(end -0.67945 -0.305054)
			(stroke
				(width 0.1)
				(type default)
			)
			(layer "F.Fab")
		)
		(pad "1" smd circle
			(at -0.40005 0 90)
			(size 0 0)
			(layers "F.Cu" "F.Mask" "F.Paste")
			(net "P3V3_AUX")
		)
		(pad "2" smd circle
			(at 0.40005 0 90)
			(size 0 0)
			(layers "F.Cu" "F.Mask" "F.Paste")
			(net "RST_MB_BMC_N")
		)
	)
	(footprint ""
		(layer "F.Cu")
		(at 224.022158 -81.627472 180)
		(property "Reference" "R4350"
			(at 0 0 180)
			(layer "F.SilkS")
			(hide yes)
			(effects
				(font
					(size 1.27 1.27)
				)
			)
		)
		(property "Value" ""
			(at 0 0 180)
			(layer "F.Fab")
			(effects
				(font
					(size 1.27 1.27)
				)
			)
		)
		(duplicate_pad_numbers_are_jumpers no)
		(fp_line
			(start 0.7874 0.4064)
			(end -0.7874 0.4064)
			(stroke
				(width 0.1524)
				(type default)
			)
			(layer "F.SilkS")
		)
		(fp_line
			(start 0.7874 -0.4064)
			(end 0.7874 0.4064)
			(stroke
				(width 0.1524)
				(type default)
			)
			(layer "F.SilkS")
		)
		(fp_line
			(start -0.7874 0.4064)
			(end -0.7874 -0.4064)
			(stroke
				(width 0.1524)
				(type default)
			)
			(layer "F.SilkS")
		)
		(fp_line
			(start -0.7874 -0.4064)
			(end 0.7874 -0.4064)
			(stroke
				(width 0.1524)
				(type default)
			)
			(layer "F.SilkS")
		)
		(fp_line
			(start 0.67945 0.3048)
			(end 0.120396 0.3048)
			(stroke
				(width 0.1)
				(type default)
			)
			(layer "F.Fab")
		)
		(fp_line
			(start 0.67945 -0.3048)
			(end 0.67945 0.3048)
			(stroke
				(width 0.1)
				(type default)
			)
			(layer "F.Fab")
		)
		(fp_line
			(start 0.12065 -0.2794)
			(end 0.12065 -0.3048)
			(stroke
				(width 0.1)
				(type default)
			)
			(layer "F.Fab")
		)
		(fp_line
			(start 0.12065 -0.3048)
			(end 0.67945 -0.3048)
			(stroke
				(width 0.1)
				(type default)
			)
			(layer "F.Fab")
		)
		(fp_line
			(start 0.120396 0.3048)
			(end 0.120396 0.2794)
			(stroke
				(width 0.1)
				(type default)
			)
			(layer "F.Fab")
		)
		(fp_line
			(start 0.120396 0.2794)
			(end -0.12065 0.2794)
			(stroke
				(width 0.1)
				(type default)
			)
			(layer "F.Fab")
		)
		(fp_line
			(start -0.12065 0.3048)
			(end -0.67945 0.3048)
			(stroke
				(width 0.1)
				(type default)
			)
			(layer "F.Fab")
		)
		(fp_line
			(start -0.12065 0.2794)
			(end -0.12065 0.3048)
			(stroke
				(width 0.1)
				(type default)
			)
			(layer "F.Fab")
		)
		(fp_line
			(start -0.12065 -0.2794)
			(end 0.12065 -0.2794)
			(stroke
				(width 0.1)
				(type default)
			)
			(layer "F.Fab")
		)
		(fp_line
			(start -0.12065 -0.305054)
			(end -0.12065 -0.2794)
			(stroke
				(width 0.1)
				(type default)
			)
			(layer "F.Fab")
		)
		(fp_line
			(start -0.67945 0.3048)
			(end -0.67945 -0.305054)
			(stroke
				(width 0.1)
				(type default)
			)
			(layer "F.Fab")
		)
		(fp_line
			(start -0.67945 -0.305054)
			(end -0.12065 -0.305054)
			(stroke
				(width 0.1)
				(type default)
			)
			(layer "F.Fab")
		)
		(pad "1" smd circle
			(at -0.40005 0 180)
			(size 0 0)
			(layers "F.Cu" "F.Mask" "F.Paste")
			(net "P3V3_AUX")
		)
		(pad "2" smd circle
			(at 0.40005 0 180)
			(size 0 0)
			(layers "F.Cu" "F.Mask" "F.Paste")
			(net "SSD12_LED_R")
		)
	)
	(footprint ""
		(layer "F.Cu")
		(at 355.61524 -20.72513)
		(property "Reference" "H104"
			(at 1.45288 -2.643886 0)
			(unlocked yes)
			(layer "B.SilkS")
			(effects
				(font
					(size 0.7874 0.5842)
					(thickness 0.1524)
				)
				(justify left mirror)
			)
		)
		(property "Value" ""
			(at 0 0 0)
			(layer "F.Fab")
			(effects
				(font
					(size 1.27 1.27)
				)
			)
		)
		(duplicate_pad_numbers_are_jumpers no)
		(pad "1" thru_hole rect
			(at 0 0)
			(size 4.2164 5.0038)
			(drill 2.0066
				(offset 0.099822 0)
			)
			(layers "*.Cu" "*.Mask")
			(remove_unused_layers no)
			(net "Net_8559")
			(clearance -0.8509)
			(padstack
				(mode front_inner_back)
				(layer "Inner"
					(shape circle)
					(size 4.0132 4.0132)
					(clearance -0.7493)
				)
				(layer "B.Cu"
					(shape circle)
					(size 4.0132 4.0132)
					(clearance -0.7493)
				)
			)
		)
	)
	(footprint ""
		(layer "F.Cu")
		(at 313.354974 -53.468524 90)
		(property "Reference" "PC583"
			(at 0 0 90)
			(layer "F.SilkS")
			(hide yes)
			(effects
				(font
					(size 1.27 1.27)
				)
			)
		)
		(property "Value" ""
			(at 0 0 90)
			(layer "F.Fab")
			(effects
				(font
					(size 1.27 1.27)
				)
			)
		)
		(duplicate_pad_numbers_are_jumpers no)
		(fp_line
			(start 1.524 -0.762)
			(end 1.524 0.762)
			(stroke
				(width 0.1524)
				(type default)
			)
			(layer "F.SilkS")
		)
		(fp_line
			(start -1.524 -0.762)
			(end 1.524 -0.762)
			(stroke
				(width 0.1524)
				(type default)
			)
			(layer "F.SilkS")
		)
		(fp_line
			(start 1.524 0.762)
			(end -1.524 0.762)
			(stroke
				(width 0.1524)
				(type default)
			)
			(layer "F.SilkS")
		)
		(fp_line
			(start -1.524 0.762)
			(end -1.524 -0.762)
			(stroke
				(width 0.1524)
				(type default)
			)
			(layer "F.SilkS")
		)
		(fp_line
			(start 1.1049 -0.724916)
			(end -1.1049 -0.724916)
			(stroke
				(width 0.1)
				(type default)
			)
			(layer "F.Fab")
		)
		(fp_line
			(start -1.1049 -0.724916)
			(end -1.1049 0.724916)
			(stroke
				(width 0.1)
				(type default)
			)
			(layer "F.Fab")
		)
		(fp_line
			(start 1.1049 0.724916)
			(end 1.1049 -0.724916)
			(stroke
				(width 0.1)
				(type default)
			)
			(layer "F.Fab")
		)
		(fp_line
			(start -1.1049 0.724916)
			(end 1.1049 0.724916)
			(stroke
				(width 0.1)
				(type default)
			)
			(layer "F.Fab")
		)
		(pad "1" smd rect
			(at -0.889 0 270)
			(size 1.016 1.27)
			(layers "F.Cu" "F.Mask" "F.Paste")
			(net "GND")
		)
		(pad "2" smd rect
			(at 0.889 0 270)
			(size 1.016 1.27)
			(layers "F.Cu" "F.Mask" "F.Paste")
			(net "P3V3_AUX")
		)
	)
	(footprint ""
		(layer "F.Cu")
		(at 238.219488 -225.427032 180)
		(property "Reference" "R6596"
			(at 0 0 180)
			(layer "F.SilkS")
			(hide yes)
			(effects
				(font
					(size 1.27 1.27)
				)
			)
		)
		(property "Value" ""
			(at 0 0 180)
			(layer "F.Fab")
			(effects
				(font
					(size 1.27 1.27)
				)
			)
		)
		(duplicate_pad_numbers_are_jumpers no)
		(fp_line
			(start 0.7874 0.4064)
			(end -0.7874 0.4064)
			(stroke
				(width 0.1524)
				(type default)
			)
			(layer "F.SilkS")
		)
		(fp_line
			(start 0.7874 -0.4064)
			(end 0.7874 0.4064)
			(stroke
				(width 0.1524)
				(type default)
			)
			(layer "F.SilkS")
		)
		(fp_line
			(start -0.7874 0.4064)
			(end -0.7874 -0.4064)
			(stroke
				(width 0.1524)
				(type default)
			)
			(layer "F.SilkS")
		)
		(fp_line
			(start -0.7874 -0.4064)
			(end 0.7874 -0.4064)
			(stroke
				(width 0.1524)
				(type default)
			)
			(layer "F.SilkS")
		)
		(fp_line
			(start 0.67945 0.3048)
			(end 0.120396 0.3048)
			(stroke
				(width 0.1)
				(type default)
			)
			(layer "F.Fab")
		)
		(fp_line
			(start 0.67945 -0.3048)
			(end 0.67945 0.3048)
			(stroke
				(width 0.1)
				(type default)
			)
			(layer "F.Fab")
		)
		(fp_line
			(start 0.12065 -0.2794)
			(end 0.12065 -0.3048)
			(stroke
				(width 0.1)
				(type default)
			)
			(layer "F.Fab")
		)
		(fp_line
			(start 0.12065 -0.3048)
			(end 0.67945 -0.3048)
			(stroke
				(width 0.1)
				(type default)
			)
			(layer "F.Fab")
		)
		(fp_line
			(start 0.120396 0.3048)
			(end 0.120396 0.2794)
			(stroke
				(width 0.1)
				(type default)
			)
			(layer "F.Fab")
		)
		(fp_line
			(start 0.120396 0.2794)
			(end -0.12065 0.2794)
			(stroke
				(width 0.1)
				(type default)
			)
			(layer "F.Fab")
		)
		(fp_line
			(start -0.12065 0.3048)
			(end -0.67945 0.3048)
			(stroke
				(width 0.1)
				(type default)
			)
			(layer "F.Fab")
		)
		(fp_line
			(start -0.12065 0.2794)
			(end -0.12065 0.3048)
			(stroke
				(width 0.1)
				(type default)
			)
			(layer "F.Fab")
		)
		(fp_line
			(start -0.12065 -0.2794)
			(end 0.12065 -0.2794)
			(stroke
				(width 0.1)
				(type default)
			)
			(layer "F.Fab")
		)
		(fp_line
			(start -0.12065 -0.305054)
			(end -0.12065 -0.2794)
			(stroke
				(width 0.1)
				(type default)
			)
			(layer "F.Fab")
		)
		(fp_line
			(start -0.67945 0.3048)
			(end -0.67945 -0.305054)
			(stroke
				(width 0.1)
				(type default)
			)
			(layer "F.Fab")
		)
		(fp_line
			(start -0.67945 -0.305054)
			(end -0.12065 -0.305054)
			(stroke
				(width 0.1)
				(type default)
			)
			(layer "F.Fab")
		)
		(pad "1" smd circle
			(at -0.40005 0 180)
			(size 0 0)
			(layers "F.Cu" "F.Mask" "F.Paste")
			(net "P1V8_PLL0_PEX3_SCALED")
		)
		(pad "2" smd circle
			(at 0.40005 0 180)
			(size 0 0)
			(layers "F.Cu" "F.Mask" "F.Paste")
			(net "GND")
		)
	)
)
